# S9S_MB_2U (Grand Teton) — schematic netlist excerpt (pin names and nets, part order shuffled) for the footprints in the layout excerpt that follows; sources: Cadence DE-HDL packaged netlist, KiCad conversion of 03242023_DA0F0TMBIJ0_F0T_Motherboard_J_brd_V01_OCP.brd

R477  Q_RES  60.4 1% CHIP  pkg 0402LF  page 179 : A = PD_PCH_XCLK_BIASREF ; B = GND
C1192  Q_CAP  22UF 4V 20% X6S  pkg C0603  page 189 : A = P1V05_PCH_AUX ; B = GND

(kicad_pcb
	(version 20260206)
	(generator "pcbnew")
	(generator_version "10.0")
	(general
		(thickness 1.6)
		(legacy_teardrops no)
	)
	(paper "A4")
	(title_block
		(title "03242023_DA0F0TMBIJ0_F0T_Motherboard_J_brd_V01_OCP.brd")
		(comment 1 "Grand Teton / footprints 4857-4858 of 6105")
	)
	(layers
		(0 "F.Cu" signal "TOP")
		(4 "In1.Cu" signal "GND")
		(6 "In2.Cu" signal "IN1")
		(8 "In3.Cu" signal "GND1")
		(10 "In4.Cu" signal "IN2")
		(12 "In5.Cu" signal "GND2")
		(14 "In6.Cu" signal "IN3")
		(16 "In7.Cu" signal "GND3")
		(18 "In8.Cu" signal "VCC")
		(20 "In9.Cu" signal "VCC1")
		(22 "In10.Cu" signal "GND4")
		(24 "In11.Cu" signal "IN4")
		(26 "In12.Cu" signal "GND5")
		(28 "In13.Cu" signal "IN5")
		(30 "In14.Cu" signal "GND6")
		(32 "In15.Cu" signal "IN6")
		(34 "In16.Cu" signal "GND7")
		(2 "B.Cu" signal "BOTTOM")
		(9 "F.Adhes" user "F.Adhesive")
		(11 "B.Adhes" user "B.Adhesive")
		(13 "F.Paste" user "Package Geometry/Pastemask Top")
		(15 "B.Paste" user "Package Geometry/Pastemask Bottom")
		(5 "F.SilkS" user "Ref Des/Silkscreen Top")
		(7 "B.SilkS" user "Ref Des/Silkscreen Bottom")
		(1 "F.Mask" user "Board Geometry/Soldermask Top")
		(3 "B.Mask" user "Board Geometry/Soldermask Bottom")
		(17 "Dwgs.User" user "User.Drawings")
		(19 "Cmts.User" user "User.Comments")
		(21 "Eco1.User" user "User.Eco1")
		(23 "Eco2.User" user "User.Eco2")
		(25 "Edge.Cuts" user "Board Geometry/Outline")
		(27 "Margin" user)
		(31 "F.CrtYd" user "Package Geometry/Place Bound Top")
		(29 "B.CrtYd" user "Package Geometry/Place Bound Bottom")
		(35 "F.Fab" user "Ref Des/Assembly Top")
		(33 "B.Fab" user "Ref Des/Assembly Bottom")
	)
	(footprint ""
		(layer "B.Cu")
		(at 340.521036 -53.908706 180)
		(property "Reference" "R477"
			(at 0 0 0)
			(layer "B.SilkS")
			(hide yes)
			(effects
				(font
					(size 1.27 1.27)
				)
				(justify mirror)
			)
		)
		(property "Value" ""
			(at 0 0 0)
			(layer "B.Fab")
			(effects
				(font
					(size 1.27 1.27)
				)
				(justify mirror)
			)
		)
		(duplicate_pad_numbers_are_jumpers no)
		(fp_line
			(start 0.7874 0.4064)
			(end 0.7874 -0.4064)
			(stroke
				(width 0.1524)
				(type default)
			)
			(layer "B.SilkS")
		)
		(fp_line
			(start 0.7874 -0.4064)
			(end -0.7874 -0.4064)
			(stroke
				(width 0.1524)
				(type default)
			)
			(layer "B.SilkS")
		)
		(fp_line
			(start -0.308864 0.4064)
			(end 0.7874 0.4064)
			(stroke
				(width 0.1524)
				(type default)
			)
			(layer "B.SilkS")
		)
		(fp_line
			(start -0.7874 -0.4064)
			(end -0.7874 0.247142)
			(stroke
				(width 0.1524)
				(type default)
			)
			(layer "B.SilkS")
		)
		(fp_line
			(start 0.67945 0.3048)
			(end 0.67945 -0.305054)
			(stroke
				(width 0.1)
				(type default)
			)
			(layer "B.Fab")
		)
		(fp_line
			(start 0.67945 -0.305054)
			(end 0.12065 -0.305054)
			(stroke
				(width 0.1)
				(type default)
			)
			(layer "B.Fab")
		)
		(fp_line
			(start 0.12065 0.3048)
			(end 0.67945 0.3048)
			(stroke
				(width 0.1)
				(type default)
			)
			(layer "B.Fab")
		)
		(fp_line
			(start 0.12065 0.2794)
			(end 0.12065 0.3048)
			(stroke
				(width 0.1)
				(type default)
			)
			(layer "B.Fab")
		)
		(fp_line
			(start 0.12065 -0.2794)
			(end -0.12065 -0.2794)
			(stroke
				(width 0.1)
				(type default)
			)
			(layer "B.Fab")
		)
		(fp_line
			(start 0.12065 -0.305054)
			(end 0.12065 -0.2794)
			(stroke
				(width 0.1)
				(type default)
			)
			(layer "B.Fab")
		)
		(fp_line
			(start -0.120396 0.3048)
			(end -0.120396 0.2794)
			(stroke
				(width 0.1)
				(type default)
			)
			(layer "B.Fab")
		)
		(fp_line
			(start -0.120396 0.2794)
			(end 0.12065 0.2794)
			(stroke
				(width 0.1)
				(type default)
			)
			(layer "B.Fab")
		)
		(fp_line
			(start -0.12065 -0.2794)
			(end -0.12065 -0.3048)
			(stroke
				(width 0.1)
				(type default)
			)
			(layer "B.Fab")
		)
		(fp_line
			(start -0.12065 -0.3048)
			(end -0.67945 -0.3048)
			(stroke
				(width 0.1)
				(type default)
			)
			(layer "B.Fab")
		)
		(fp_line
			(start -0.67945 0.3048)
			(end -0.120396 0.3048)
			(stroke
				(width 0.1)
				(type default)
			)
			(layer "B.Fab")
		)
		(fp_line
			(start -0.67945 -0.3048)
			(end -0.67945 0.3048)
			(stroke
				(width 0.1)
				(type default)
			)
			(layer "B.Fab")
		)
		(pad "1" smd circle
			(at 0.40005 0)
			(size 0 0)
			(layers "B.Cu" "B.Mask" "B.Paste")
			(net "PD_PCH_XCLK_BIASREF")
		)
		(pad "2" smd circle
			(at -0.40005 0)
			(size 0 0)
			(layers "B.Cu" "B.Mask" "B.Paste")
			(net "GND")
		)
	)
	(footprint ""
		(layer "B.Cu")
		(at 302.218852 -54.389782 180)
		(property "Reference" "C1192"
			(at 0 0 0)
			(layer "B.SilkS")
			(hide yes)
			(effects
				(font
					(size 1.27 1.27)
				)
				(justify mirror)
			)
		)
		(property "Value" ""
			(at 0 0 0)
			(layer "B.Fab")
			(effects
				(font
					(size 1.27 1.27)
				)
				(justify mirror)
			)
		)
		(duplicate_pad_numbers_are_jumpers no)
		(fp_line
			(start 1.2954 0.5842)
			(end 1.2954 -0.5842)
			(stroke
				(width 0.1524)
				(type default)
			)
			(layer "B.SilkS")
		)
		(fp_line
			(start 1.2954 -0.5842)
			(end -1.2954 -0.5842)
			(stroke
				(width 0.1524)
				(type default)
			)
			(layer "B.SilkS")
		)
		(fp_line
			(start 0 -0.5842)
			(end 0 0.5842)
			(stroke
				(width 0.1524)
				(type default)
			)
			(layer "B.SilkS")
		)
		(fp_line
			(start -1.2954 0.5842)
			(end 1.2954 0.5842)
			(stroke
				(width 0.1524)
				(type default)
			)
			(layer "B.SilkS")
		)
		(fp_line
			(start -1.2954 -0.5842)
			(end -1.2954 0.5842)
			(stroke
				(width 0.1524)
				(type default)
			)
			(layer "B.SilkS")
		)
		(fp_line
			(start 1.1938 0.4064)
			(end 1.1938 -0.4064)
			(stroke
				(width 0.1)
				(type default)
			)
			(layer "B.Fab")
		)
		(fp_line
			(start 1.1938 -0.4064)
			(end 0.8636 -0.4064)
			(stroke
				(width 0.1)
				(type default)
			)
			(layer "B.Fab")
		)
		(fp_line
			(start 0.8636 0.4572)
			(end 0.8636 0.4064)
			(stroke
				(width 0.1)
				(type default)
			)
			(layer "B.Fab")
		)
		(fp_line
			(start 0.8636 0.4064)
			(end 1.1938 0.4064)
			(stroke
				(width 0.1)
				(type default)
			)
			(layer "B.Fab")
		)
		(fp_line
			(start 0.8636 -0.4064)
			(end 0.8636 -0.4572)
			(stroke
				(width 0.1)
				(type default)
			)
			(layer "B.Fab")
		)
		(fp_line
			(start 0.8636 -0.4572)
			(end -0.8636 -0.4572)
			(stroke
				(width 0.1)
				(type default)
			)
			(layer "B.Fab")
		)
		(fp_line
			(start -0.8636 0.4572)
			(end 0.8636 0.4572)
			(stroke
				(width 0.1)
				(type default)
			)
			(layer "B.Fab")
		)
		(fp_line
			(start -0.8636 0.4064)
			(end -0.8636 0.4572)
			(stroke
				(width 0.1)
				(type default)
			)
			(layer "B.Fab")
		)
		(fp_line
			(start -0.8636 -0.4064)
			(end -1.1938 -0.4064)
			(stroke
				(width 0.1)
				(type default)
			)
			(layer "B.Fab")
		)
		(fp_line
			(start -0.8636 -0.4572)
			(end -0.8636 -0.4064)
			(stroke
				(width 0.1)
				(type default)
			)
			(layer "B.Fab")
		)
		(fp_line
			(start -1.1938 0.4064)
			(end -0.8636 0.4064)
			(stroke
				(width 0.1)
				(type default)
			)
			(layer "B.Fab")
		)
		(fp_line
			(start -1.1938 -0.4064)
			(end -1.1938 0.4064)
			(stroke
				(width 0.1)
				(type default)
			)
			(layer "B.Fab")
		)
		(pad "1" smd rect
			(at 0.7366 0 90)
			(size 0.7112 0.8128)
			(layers "B.Cu" "B.Mask" "B.Paste")
			(net "P1V05_PCH_AUX")
		)
		(pad "2" smd rect
			(at -0.7366 0 90)
			(size 0.7112 0.8128)
			(layers "B.Cu" "B.Mask" "B.Paste")
			(net "GND")
		)
	)
)
